(kicad_pcb
	(version 20260206)
	(generator "pcbnew")
	(generator_version "10.0")
	(general
		(thickness 1.6)
		(legacy_teardrops no)
	)
	(paper "A4")
	(title_block
		(title "03242023_DA0F0TMBIJ0_F0T_Motherboard_J_brd_V01_OCP.brd")
		(comment 1 "Grand Teton / footprint 1682 of 6105 (U1), pads 319-426 of 4677")
	)
	(layers
		(0 "F.Cu" signal "TOP")
		(4 "In1.Cu" signal "GND")
		(6 "In2.Cu" signal "IN1")
		(8 "In3.Cu" signal "GND1")
		(10 "In4.Cu" signal "IN2")
		(12 "In5.Cu" signal "GND2")
		(14 "In6.Cu" signal "IN3")
		(16 "In7.Cu" signal "GND3")
		(18 "In8.Cu" signal "VCC")
		(20 "In9.Cu" signal "VCC1")
		(22 "In10.Cu" signal "GND4")
		(24 "In11.Cu" signal "IN4")
		(26 "In12.Cu" signal "GND5")
		(28 "In13.Cu" signal "IN5")
		(30 "In14.Cu" signal "GND6")
		(32 "In15.Cu" signal "IN6")
		(34 "In16.Cu" signal "GND7")
		(2 "B.Cu" signal "BOTTOM")
		(9 "F.Adhes" user "F.Adhesive")
		(11 "B.Adhes" user "B.Adhesive")
		(13 "F.Paste" user "Package Geometry/Pastemask Top")
		(15 "B.Paste" user "Package Geometry/Pastemask Bottom")
		(5 "F.SilkS" user "Ref Des/Silkscreen Top")
		(7 "B.SilkS" user "Ref Des/Silkscreen Bottom")
		(1 "F.Mask" user "Board Geometry/Soldermask Top")
		(3 "B.Mask" user "Board Geometry/Soldermask Bottom")
		(17 "Dwgs.User" user "User.Drawings")
		(19 "Cmts.User" user "User.Comments")
		(21 "Eco1.User" user "User.Eco1")
		(23 "Eco2.User" user "User.Eco2")
		(25 "Edge.Cuts" user "Board Geometry/Outline")
		(27 "Margin" user)
		(31 "F.CrtYd" user "Package Geometry/Place Bound Top")
		(29 "B.CrtYd" user "Package Geometry/Place Bound Bottom")
		(35 "F.Fab" user "Ref Des/Assembly Top")
		(33 "B.Fab" user "Ref Des/Assembly Bottom")
	)
	(footprint ""
		(layer "F.Cu")
		(at 111.93018 -251.76988 90)
		(property "Reference" "U1"
			(at -74.913236 41.548812 0)
			(unlocked yes)
			(layer "F.SilkS")
			(effects
				(font
					(size 1.6002 1.1938)
					(thickness 0.1524)
				)
				(justify left)
			)
		)
		(property "Value" ""
			(at 0 0 90)
			(layer "F.Fab")
			(effects
				(font
					(size 1.27 1.27)
				)
			)
		)
		(duplicate_pad_numbers_are_jumpers no)
		(pad "AG45" smd circle
			(at -1.613916 -14.856714 270)
			(size 0.4318 0.4318)
			(layers "F.Cu" "F.Mask" "F.Paste")
			(net "GND")
		)
		(pad "AG48" smd circle
			(at 2.427732 -14.746732 270)
			(size 0.4318 0.4318)
			(layers "F.Cu" "F.Mask" "F.Paste")
			(net "M_C_CPU1_SB_RSP<0>")
		)
		(pad "AG50" smd circle
			(at 4.055618 -14.746732 270)
			(size 0.4318 0.4318)
			(layers "F.Cu" "F.Mask" "F.Paste")
			(net "M_D_CPU1_SB_RSP<1>")
		)
		(pad "AG52" smd circle
			(at 5.68325 -14.746732 270)
			(size 0.4318 0.4318)
			(layers "F.Cu" "F.Mask" "F.Paste")
			(net "GND")
		)
		(pad "AG54" smd circle
			(at 7.311136 -14.746732 270)
			(size 0.4318 0.4318)
			(layers "F.Cu" "F.Mask" "F.Paste")
			(net "M_C_CPU1_SA_CB<6>")
		)
		(pad "AG56" smd circle
			(at 8.939022 -14.746732 270)
			(size 0.4318 0.4318)
			(layers "F.Cu" "F.Mask" "F.Paste")
			(net "M_C_CPU1_SA_CB<3>")
		)
		(pad "AG58" smd circle
			(at 10.566654 -14.746732 270)
			(size 0.4318 0.4318)
			(layers "F.Cu" "F.Mask" "F.Paste")
			(net "GND")
		)
		(pad "AG60" smd circle
			(at 12.19454 -14.746732 270)
			(size 0.4318 0.4318)
			(layers "F.Cu" "F.Mask" "F.Paste")
			(net "M_C_CPU1_SA_DQ<30>")
		)
		(pad "AG62" smd circle
			(at 13.822426 -14.746732 270)
			(size 0.4318 0.4318)
			(layers "F.Cu" "F.Mask" "F.Paste")
			(net "M_C_CPU1_SA_DQ<27>")
		)
		(pad "AG64" smd circle
			(at 15.450058 -14.746732 270)
			(size 0.4318 0.4318)
			(layers "F.Cu" "F.Mask" "F.Paste")
			(net "GND")
		)
		(pad "AG66" smd circle
			(at 17.07769 -14.746732 270)
			(size 0.4318 0.4318)
			(layers "F.Cu" "F.Mask" "F.Paste")
			(net "M_C_CPU1_SA_DQ<14>")
		)
		(pad "AG68" smd circle
			(at 18.705576 -14.746732 270)
			(size 0.4318 0.4318)
			(layers "F.Cu" "F.Mask" "F.Paste")
			(net "M_C_CPU1_SA_DQ<11>")
		)
		(pad "AG70" smd circle
			(at 20.333462 -14.746732 270)
			(size 0.4318 0.4318)
			(layers "F.Cu" "F.Mask" "F.Paste")
			(net "GND")
		)
		(pad "AG72" smd circle
			(at 21.961094 -14.746732 270)
			(size 0.4318 0.4318)
			(layers "F.Cu" "F.Mask" "F.Paste")
			(net "M_D_CPU1_SA_DQ<6>")
		)
		(pad "AG74" smd circle
			(at 23.58898 -14.746732 270)
			(size 0.4318 0.4318)
			(layers "F.Cu" "F.Mask" "F.Paste")
			(net "M_D_CPU1_SA_DQ<3>")
		)
		(pad "AG76" smd circle
			(at 25.216612 -14.746732 270)
			(size 0.4318 0.4318)
			(layers "F.Cu" "F.Mask" "F.Paste")
			(net "GND")
		)
		(pad "AG78" smd circle
			(at 26.844498 -14.746732 270)
			(size 0.4318 0.4318)
			(layers "F.Cu" "F.Mask" "F.Paste")
			(net "PVCCFA_EHV_FIVRA_CPU1")
		)
		(pad "AG80" smd circle
			(at 28.472384 -14.746732 270)
			(size 0.4318 0.4318)
			(layers "F.Cu" "F.Mask" "F.Paste")
			(net "UPI_CPU0_CPU1_P2P2_DP<8>")
		)
		(pad "AG82" smd circle
			(at 30.100016 -14.746732 270)
			(size 0.4318 0.4318)
			(layers "F.Cu" "F.Mask" "F.Paste")
			(net "UPI_CPU0_CPU1_P2P2_DN<11>")
		)
		(pad "AG84" smd circle
			(at 31.727902 -14.746732 270)
			(size 0.4318 0.4318)
			(layers "F.Cu" "F.Mask" "F.Paste")
			(net "GND")
		)
		(pad "AG86" smd circle
			(at 33.355534 -14.746732 270)
			(size 0.4318 0.4318)
			(layers "F.Cu" "F.Mask" "F.Paste")
			(net "P5E_CPU1_PE4_TX_DN<8>")
		)
		(pad "AG88" smd circle
			(at 34.98342 -14.746732 270)
			(size 0.4318 0.4318)
			(layers "F.Cu" "F.Mask" "F.Paste")
			(net "GND")
		)
		(pad "AG90" smd circle
			(at 36.611306 -14.746732 270)
			(size 0.4318 0.4318)
			(layers "F.Cu" "F.Mask" "F.Paste")
			(net "P5E_CPU1_PE4_RX_DP<8>")
		)
		(pad "AH2" smd circle
			(at -36.611306 -14.387068 270)
			(size 0.4318 0.4318)
			(layers "F.Cu" "F.Mask" "F.Paste")
			(net "UPI_CPU1_CPU0_P0P1_DN<9>")
		)
		(pad "AH4" smd circle
			(at -34.98342 -14.387068 270)
			(size 0.4318 0.4318)
			(layers "F.Cu" "F.Mask" "F.Paste")
			(net "GND")
		)
		(pad "AH6" smd circle
			(at -33.355534 -14.387068 270)
			(size 0.4318 0.4318)
			(layers "F.Cu" "F.Mask" "F.Paste")
			(net "UPI_CPU0_CPU1_P1P0_DN<9>")
		)
		(pad "AH8" smd circle
			(at -31.727902 -14.387068 270)
			(size 0.4318 0.4318)
			(layers "F.Cu" "F.Mask" "F.Paste")
			(net "GND")
		)
		(pad "AH10" smd circle
			(at -30.100016 -14.387068 270)
			(size 0.4318 0.4318)
			(layers "F.Cu" "F.Mask" "F.Paste")
			(net "P5E_CPU1_PE0_RX_DP<9>")
		)
		(pad "AH12" smd circle
			(at -28.472384 -14.387068 270)
			(size 0.4318 0.4318)
			(layers "F.Cu" "F.Mask" "F.Paste")
			(net "GND")
		)
		(pad "AH14" smd circle
			(at -26.844498 -14.387068 270)
			(size 0.4318 0.4318)
			(layers "F.Cu" "F.Mask" "F.Paste")
			(net "P5E_CPU1_PE0_TX_DP<8>")
		)
		(pad "AH16" smd circle
			(at -25.216612 -14.387068 270)
			(size 0.4318 0.4318)
			(layers "F.Cu" "F.Mask" "F.Paste")
			(net "GND")
		)
		(pad "AH18" smd circle
			(at -23.58898 -14.387068 270)
			(size 0.4318 0.4318)
			(layers "F.Cu" "F.Mask" "F.Paste")
			(net "M_C_CPU1_SB_DQS_DP<8>")
		)
		(pad "AH20" smd circle
			(at -21.961094 -14.387068 270)
			(size 0.4318 0.4318)
			(layers "F.Cu" "F.Mask" "F.Paste")
			(net "GND")
		)
		(pad "AH22" smd circle
			(at -20.333462 -14.387068 270)
			(size 0.4318 0.4318)
			(layers "F.Cu" "F.Mask" "F.Paste")
			(net "GND")
		)
		(pad "AH24" smd circle
			(at -18.705576 -14.387068 270)
			(size 0.4318 0.4318)
			(layers "F.Cu" "F.Mask" "F.Paste")
			(net "M_D_CPU1_SB_DQS_DP<7>")
		)
		(pad "AH26" smd circle
			(at -17.07769 -14.387068 270)
			(size 0.4318 0.4318)
			(layers "F.Cu" "F.Mask" "F.Paste")
			(net "GND")
		)
		(pad "AH28" smd circle
			(at -15.450058 -14.387068 270)
			(size 0.4318 0.4318)
			(layers "F.Cu" "F.Mask" "F.Paste")
			(net "GND")
		)
		(pad "AH30" smd circle
			(at -13.822426 -14.387068 270)
			(size 0.4318 0.4318)
			(layers "F.Cu" "F.Mask" "F.Paste")
			(net "M_C_CPU1_SB_DQS_DP<6>")
		)
		(pad "AH32" smd circle
			(at -12.19454 -14.387068 270)
			(size 0.4318 0.4318)
			(layers "F.Cu" "F.Mask" "F.Paste")
			(net "GND")
		)
		(pad "AH34" smd circle
			(at -10.566654 -14.387068 270)
			(size 0.4318 0.4318)
			(layers "F.Cu" "F.Mask" "F.Paste")
			(net "GND")
		)
		(pad "AH36" smd circle
			(at -8.939022 -14.387068 270)
			(size 0.4318 0.4318)
			(layers "F.Cu" "F.Mask" "F.Paste")
			(net "M_C_CPU1_SB_DQS_DP<5>")
		)
		(pad "AH38" smd circle
			(at -7.311136 -14.387068 270)
			(size 0.4318 0.4318)
			(layers "F.Cu" "F.Mask" "F.Paste")
			(net "GND")
		)
		(pad "AH40" smd circle
			(at -5.68325 -14.387068 270)
			(size 0.4318 0.4318)
			(layers "F.Cu" "F.Mask" "F.Paste")
			(net "GND")
		)
		(pad "AH42" smd circle
			(at -4.055618 -14.387068 270)
			(size 0.4318 0.4318)
			(layers "F.Cu" "F.Mask" "F.Paste")
			(net "M_D_CPU1_SB_PAR")
		)
		(pad "AH44" smd circle
			(at -2.427732 -14.387068 270)
			(size 0.4318 0.4318)
			(layers "F.Cu" "F.Mask" "F.Paste")
			(net "GND")
		)
		(pad "AH47" smd circle
			(at 1.613916 -14.277086 270)
			(size 0.4318 0.4318)
			(layers "F.Cu" "F.Mask" "F.Paste")
			(net "GND")
		)
		(pad "AH49" smd circle
			(at 3.241802 -14.277086 270)
			(size 0.4318 0.4318)
			(layers "F.Cu" "F.Mask" "F.Paste")
			(net "M_C_CPU1_CLK_DP<1>")
		)
		(pad "AH51" smd circle
			(at 4.869434 -14.277086 270)
			(size 0.4318 0.4318)
			(layers "F.Cu" "F.Mask" "F.Paste")
			(net "GND")
		)
		(pad "AH53" smd circle
			(at 6.49732 -14.277086 270)
			(size 0.4318 0.4318)
			(layers "F.Cu" "F.Mask" "F.Paste")
			(net "GND")
		)
		(pad "AH55" smd circle
			(at 8.124952 -14.277086 270)
			(size 0.4318 0.4318)
			(layers "F.Cu" "F.Mask" "F.Paste")
			(net "M_C_CPU1_SA_DQS_DN<9>")
		)
		(pad "AH57" smd circle
			(at 9.752838 -14.277086 270)
			(size 0.4318 0.4318)
			(layers "F.Cu" "F.Mask" "F.Paste")
			(net "GND")
		)
		(pad "AH59" smd circle
			(at 11.380724 -14.277086 270)
			(size 0.4318 0.4318)
			(layers "F.Cu" "F.Mask" "F.Paste")
			(net "GND")
		)
		(pad "AH61" smd circle
			(at 13.008356 -14.277086 270)
			(size 0.4318 0.4318)
			(layers "F.Cu" "F.Mask" "F.Paste")
			(net "M_C_CPU1_SA_DQS_DP<8>")
		)
		(pad "AH63" smd circle
			(at 14.635988 -14.277086 270)
			(size 0.4318 0.4318)
			(layers "F.Cu" "F.Mask" "F.Paste")
			(net "GND")
		)
		(pad "AH65" smd circle
			(at 16.263874 -14.277086 270)
			(size 0.4318 0.4318)
			(layers "F.Cu" "F.Mask" "F.Paste")
			(net "GND")
		)
		(pad "AH67" smd circle
			(at 17.89176 -14.277086 270)
			(size 0.4318 0.4318)
			(layers "F.Cu" "F.Mask" "F.Paste")
			(net "M_C_CPU1_SA_DQS_DN<6>")
		)
		(pad "AH69" smd circle
			(at 19.519392 -14.277086 270)
			(size 0.4318 0.4318)
			(layers "F.Cu" "F.Mask" "F.Paste")
			(net "GND")
		)
		(pad "AH71" smd circle
			(at 21.147278 -14.277086 270)
			(size 0.4318 0.4318)
			(layers "F.Cu" "F.Mask" "F.Paste")
			(net "GND")
		)
		(pad "AH73" smd circle
			(at 22.77491 -14.277086 270)
			(size 0.4318 0.4318)
			(layers "F.Cu" "F.Mask" "F.Paste")
			(net "M_D_CPU1_SA_DQS_DN<5>")
		)
		(pad "AH75" smd circle
			(at 24.402796 -14.277086 270)
			(size 0.4318 0.4318)
			(layers "F.Cu" "F.Mask" "F.Paste")
			(net "GND")
		)
		(pad "AH77" smd circle
			(at 26.030682 -14.277086 270)
			(size 0.4318 0.4318)
			(layers "F.Cu" "F.Mask" "F.Paste")
			(net "GND")
		)
		(pad "AH79" smd circle
			(at 27.658314 -14.277086 270)
			(size 0.4318 0.4318)
			(layers "F.Cu" "F.Mask" "F.Paste")
			(net "GND")
		)
		(pad "AH81" smd circle
			(at 29.2862 -14.277086 270)
			(size 0.4318 0.4318)
			(layers "F.Cu" "F.Mask" "F.Paste")
			(net "UPI_CPU0_CPU1_P2P2_DP<10>")
		)
		(pad "AH83" smd circle
			(at 30.914086 -14.277086 270)
			(size 0.4318 0.4318)
			(layers "F.Cu" "F.Mask" "F.Paste")
			(net "GND")
		)
		(pad "AH85" smd circle
			(at 32.541718 -14.277086 270)
			(size 0.4318 0.4318)
			(layers "F.Cu" "F.Mask" "F.Paste")
			(net "PVCCFA_EHV_FIVRA_CPU1")
		)
		(pad "AH87" smd circle
			(at 34.169604 -14.277086 270)
			(size 0.4318 0.4318)
			(layers "F.Cu" "F.Mask" "F.Paste")
			(net "P5E_CPU1_PE4_TX_DP<8>")
		)
		(pad "AH89" smd circle
			(at 35.797236 -14.277086 270)
			(size 0.4318 0.4318)
			(layers "F.Cu" "F.Mask" "F.Paste")
			(net "PVCCFA_EHV_FIVRA_CPU1")
		)
		(pad "AH91" smd oval
			(at 37.425122 -14.277086)
			(size 0.381 0.4826)
			(drill
				(offset 0 -0.0508)
			)
			(layers "F.Cu" "F.Mask" "F.Paste")
			(net "P5E_CPU1_PE4_RX_DN<8>")
		)
		(pad "AJ1" smd oval
			(at -37.425122 -13.916914 180)
			(size 0.381 0.4826)
			(drill
				(offset 0 -0.0508)
			)
			(layers "F.Cu" "F.Mask" "F.Paste")
			(net "UPI_CPU1_CPU0_P0P1_DP<10>")
		)
		(pad "AJ3" smd circle
			(at -35.797236 -13.916914 270)
			(size 0.4318 0.4318)
			(layers "F.Cu" "F.Mask" "F.Paste")
			(net "PVCCFA_EHV_CPU1")
		)
		(pad "AJ5" smd circle
			(at -34.169604 -13.916914 270)
			(size 0.4318 0.4318)
			(layers "F.Cu" "F.Mask" "F.Paste")
			(net "UPI_CPU0_CPU1_P1P0_DP<9>")
		)
		(pad "AJ7" smd circle
			(at -32.541718 -13.916914 270)
			(size 0.4318 0.4318)
			(layers "F.Cu" "F.Mask" "F.Paste")
			(net "PVCCFA_EHV_FIVRA_CPU1")
		)
		(pad "AJ9" smd circle
			(at -30.914086 -13.916914 270)
			(size 0.4318 0.4318)
			(layers "F.Cu" "F.Mask" "F.Paste")
			(net "P5E_CPU1_PE0_RX_DN<9>")
		)
		(pad "AJ11" smd circle
			(at -29.2862 -13.916914 270)
			(size 0.4318 0.4318)
			(layers "F.Cu" "F.Mask" "F.Paste")
			(net "PVCCFA_EHV_FIVRA_CPU1")
		)
		(pad "AJ13" smd circle
			(at -27.658314 -13.916914 270)
			(size 0.4318 0.4318)
			(layers "F.Cu" "F.Mask" "F.Paste")
			(net "P5E_CPU1_PE0_TX_DN<8>")
		)
		(pad "AJ15" smd circle
			(at -26.030682 -13.916914 270)
			(size 0.4318 0.4318)
			(layers "F.Cu" "F.Mask" "F.Paste")
			(net "PVCCFA_EHV_FIVRA_CPU1")
		)
		(pad "AJ17" smd circle
			(at -24.402796 -13.916914 270)
			(size 0.4318 0.4318)
			(layers "F.Cu" "F.Mask" "F.Paste")
			(net "M_C_CPU1_SB_DQ<31>")
		)
		(pad "AJ19" smd circle
			(at -22.77491 -13.916914 270)
			(size 0.4318 0.4318)
			(layers "F.Cu" "F.Mask" "F.Paste")
			(net "GND")
		)
		(pad "AJ21" smd circle
			(at -21.147278 -13.916914 270)
			(size 0.4318 0.4318)
			(layers "F.Cu" "F.Mask" "F.Paste")
			(net "M_D_CPU1_SB_DQS_DN<3>")
		)
		(pad "AJ23" smd circle
			(at -19.519392 -13.916914 270)
			(size 0.4318 0.4318)
			(layers "F.Cu" "F.Mask" "F.Paste")
			(net "GND")
		)
		(pad "AJ25" smd circle
			(at -17.89176 -13.916914 270)
			(size 0.4318 0.4318)
			(layers "F.Cu" "F.Mask" "F.Paste")
			(net "GND")
		)
		(pad "AJ27" smd circle
			(at -16.263874 -13.916914 270)
			(size 0.4318 0.4318)
			(layers "F.Cu" "F.Mask" "F.Paste")
			(net "M_D_CPU1_SB_DQS_DN<1>")
		)
		(pad "AJ29" smd circle
			(at -14.635988 -13.916914 270)
			(size 0.4318 0.4318)
			(layers "F.Cu" "F.Mask" "F.Paste")
			(net "GND")
		)
		(pad "AJ31" smd circle
			(at -13.008356 -13.916914 270)
			(size 0.4318 0.4318)
			(layers "F.Cu" "F.Mask" "F.Paste")
			(net "GND")
		)
		(pad "AJ33" smd circle
			(at -11.380724 -13.916914 270)
			(size 0.4318 0.4318)
			(layers "F.Cu" "F.Mask" "F.Paste")
			(net "M_D_CPU1_SB_DQS_DN<0>")
		)
		(pad "AJ35" smd circle
			(at -9.752838 -13.916914 270)
			(size 0.4318 0.4318)
			(layers "F.Cu" "F.Mask" "F.Paste")
			(net "GND")
		)
		(pad "AJ37" smd circle
			(at -8.124952 -13.916914 270)
			(size 0.4318 0.4318)
			(layers "F.Cu" "F.Mask" "F.Paste")
			(net "GND")
		)
		(pad "AJ39" smd circle
			(at -6.49732 -13.916914 270)
			(size 0.4318 0.4318)
			(layers "F.Cu" "F.Mask" "F.Paste")
			(net "M_D_CPU1_SB_DQS_DN<9>")
		)
		(pad "AJ41" smd circle
			(at -4.869434 -13.916914 270)
			(size 0.4318 0.4318)
			(layers "F.Cu" "F.Mask" "F.Paste")
			(net "GND")
		)
		(pad "AJ43" smd circle
			(at -3.241802 -13.916914 270)
			(size 0.4318 0.4318)
			(layers "F.Cu" "F.Mask" "F.Paste")
			(net "GND")
		)
		(pad "AJ45" smd circle
			(at -1.613916 -13.916914 270)
			(size 0.4318 0.4318)
			(layers "F.Cu" "F.Mask" "F.Paste")
			(net "M_D_CPU1_CLK_DN<0>")
		)
		(pad "AJ48" smd circle
			(at 2.427732 -13.806932 270)
			(size 0.4318 0.4318)
			(layers "F.Cu" "F.Mask" "F.Paste")
			(net "GND")
		)
		(pad "AJ50" smd circle
			(at 4.055618 -13.806932 270)
			(size 0.4318 0.4318)
			(layers "F.Cu" "F.Mask" "F.Paste")
			(net "GND")
		)
		(pad "AJ52" smd circle
			(at 5.68325 -13.806932 270)
			(size 0.4318 0.4318)
			(layers "F.Cu" "F.Mask" "F.Paste")
			(net "M_D_CPU1_SA_CA<0>")
		)
		(pad "AJ54" smd circle
			(at 7.311136 -13.806932 270)
			(size 0.4318 0.4318)
			(layers "F.Cu" "F.Mask" "F.Paste")
			(net "GND")
		)
		(pad "AJ56" smd circle
			(at 8.939022 -13.806932 270)
			(size 0.4318 0.4318)
			(layers "F.Cu" "F.Mask" "F.Paste")
			(net "GND")
		)
		(pad "AJ58" smd circle
			(at 10.566654 -13.806932 270)
			(size 0.4318 0.4318)
			(layers "F.Cu" "F.Mask" "F.Paste")
			(net "M_D_CPU1_SA_DQS_DN<4>")
		)
		(pad "AJ60" smd circle
			(at 12.19454 -13.806932 270)
			(size 0.4318 0.4318)
			(layers "F.Cu" "F.Mask" "F.Paste")
			(net "GND")
		)
		(pad "AJ62" smd circle
			(at 13.822426 -13.806932 270)
			(size 0.4318 0.4318)
			(layers "F.Cu" "F.Mask" "F.Paste")
			(net "GND")
		)
		(pad "AJ64" smd circle
			(at 15.450058 -13.806932 270)
			(size 0.4318 0.4318)
			(layers "F.Cu" "F.Mask" "F.Paste")
			(net "M_D_CPU1_SA_DQS_DN<3>")
		)
		(pad "AJ66" smd circle
			(at 17.07769 -13.806932 270)
			(size 0.4318 0.4318)
			(layers "F.Cu" "F.Mask" "F.Paste")
			(net "GND")
		)
		(pad "AJ68" smd circle
			(at 18.705576 -13.806932 270)
			(size 0.4318 0.4318)
			(layers "F.Cu" "F.Mask" "F.Paste")
			(net "GND")
		)
		(pad "AJ70" smd circle
			(at 20.333462 -13.806932 270)
			(size 0.4318 0.4318)
			(layers "F.Cu" "F.Mask" "F.Paste")
			(net "M_D_CPU1_SA_DQS_DN<2>")
		)
		(pad "AJ72" smd circle
			(at 21.961094 -13.806932 270)
			(size 0.4318 0.4318)
			(layers "F.Cu" "F.Mask" "F.Paste")
			(net "GND")
		)
		(pad "AJ74" smd circle
			(at 23.58898 -13.806932 270)
			(size 0.4318 0.4318)
			(layers "F.Cu" "F.Mask" "F.Paste")
			(net "GND")
		)
		(pad "AJ76" smd circle
			(at 25.216612 -13.806932 270)
			(size 0.4318 0.4318)
			(layers "F.Cu" "F.Mask" "F.Paste")
			(net "M_D_CPU1_SA_DQS_DN<1>")
		)
		(pad "AJ78" smd circle
			(at 26.844498 -13.806932 270)
			(size 0.4318 0.4318)
			(layers "F.Cu" "F.Mask" "F.Paste")
			(net "GND")
		)
		(pad "AJ80" smd circle
			(at 28.472384 -13.806932 270)
			(size 0.4318 0.4318)
			(layers "F.Cu" "F.Mask" "F.Paste")
			(net "UPI_CPU0_CPU1_P2P2_DN<10>")
		)
	)
)
